(kicad_pcb
	(version 20260206)
	(generator "pcbnew")
	(generator_version "10.0")
	(general
		(thickness 1.6)
		(legacy_teardrops no)
	)
	(paper "A4")
	(title_block
		(title "pdpb — Lightning_PDPB_BRD.brd")
		(comment 1 "Lightning (Wiwynn / Facebook NVMe JBOF) / footprints 988-994 of 1140")
	)
	(layers
		(0 "F.Cu" signal "TOP")
		(4 "In1.Cu" signal "L2GND")
		(6 "In2.Cu" signal "L3")
		(8 "In3.Cu" signal "L4VCC")
		(10 "In4.Cu" signal "L5VCC")
		(12 "In5.Cu" signal "L6")
		(14 "In6.Cu" signal "L7GND")
		(2 "B.Cu" signal "BOTTOM")
		(9 "F.Adhes" user "F.Adhesive")
		(11 "B.Adhes" user "B.Adhesive")
		(13 "F.Paste" user "Package Geometry/Pastemask Top")
		(15 "B.Paste" user "Package Geometry/Pastemask Bottom")
		(5 "F.SilkS" user "Ref Des/Silkscreen Top")
		(7 "B.SilkS" user "Ref Des/Silkscreen Bottom")
		(1 "F.Mask" user "Board Geometry/Soldermask Top")
		(3 "B.Mask" user "Board Geometry/Soldermask Bottom")
		(17 "Dwgs.User" user "User.Drawings")
		(19 "Cmts.User" user "User.Comments")
		(21 "Eco1.User" user "User.Eco1")
		(23 "Eco2.User" user "User.Eco2")
		(25 "Edge.Cuts" user "Board Geometry/Outline")
		(27 "Margin" user)
		(31 "F.CrtYd" user "Package Geometry/Place Bound Top")
		(29 "B.CrtYd" user "Package Geometry/Place Bound Bottom")
		(35 "F.Fab" user "Ref Des/Assembly Top")
		(33 "B.Fab" user "Ref Des/Assembly Bottom")
	)
	(footprint ""
		(layer "F.Cu")
		(at 77.4954 -100.2792)
		(property "Reference" "R9976"
			(at 0 0 0)
			(layer "F.SilkS")
			(hide yes)
			(effects
				(font
					(size 1.27 1.27)
				)
			)
		)
		(property "Value" "56R2F-1-GP"
			(at 0.064008 -3.993896 0)
			(unlocked yes)
			(layer "F.Fab")
			(hide yes)
			(effects
				(font
					(size 1.016 1.016)
					(thickness 0.1524)
				)
			)
		)
		(property "Device Type" "R402H16"
			(at 0.064008 -5.517896 0)
			(unlocked yes)
			(layer "F.Fab")
			(hide yes)
			(effects
				(font
					(size 1.016 1.016)
					(thickness 0.1524)
				)
			)
		)
		(duplicate_pad_numbers_are_jumpers no)
		(fp_line
			(start -0.508 -0.9398)
			(end -0.508 0.9398)
			(stroke
				(width 0.1524)
				(type default)
			)
			(layer "F.SilkS")
		)
		(fp_line
			(start 0.508 -0.9398)
			(end -0.508 -0.9398)
			(stroke
				(width 0.1524)
				(type default)
			)
			(layer "F.SilkS")
		)
		(fp_rect
			(start -0.508 0.9398)
			(end 0.508 -0.9398)
			(stroke
				(width 0)
				(type default)
			)
			(fill no)
			(layer "F.CrtYd")
		)
		(fp_rect
			(start -0.508 0.9398)
			(end 0.508 -0.9398)
			(stroke
				(width 0)
				(type default)
			)
			(fill no)
			(layer "F.Fab")
		)
		(pad "1" smd custom
			(at 0 -0.4445)
			(size 0.1397 0.1397)
			(layers "F.Cu" "F.Mask" "F.Paste")
			(net "PE_100M_CLK1_N")
			(options
				(clearance outline)
				(anchor circle)
			)
			(primitives
				(gr_poly
					(pts
						(arc
							(start -0.1778 -0.2794)
							(mid -0.249642 -0.249642)
							(end -0.2794 -0.1778)
						)
						(arc
							(start -0.2794 0.1778)
							(mid -0.249642 0.249642)
							(end -0.1778 0.2794)
						)
						(arc
							(start 0.1778 0.2794)
							(mid 0.249642 0.249642)
							(end 0.2794 0.1778)
						)
						(arc
							(start 0.2794 -0.1778)
							(mid 0.249642 -0.249642)
							(end 0.1778 -0.2794)
						)
					)
					(width 0)
					(fill yes)
				)
			)
		)
		(pad "2" smd custom
			(at 0 0.4445)
			(size 0.1397 0.1397)
			(layers "F.Cu" "F.Mask" "F.Paste")
			(net "GND")
			(options
				(clearance outline)
				(anchor circle)
			)
			(primitives
				(gr_poly
					(pts
						(arc
							(start -0.1778 -0.2794)
							(mid -0.249642 -0.249642)
							(end -0.2794 -0.1778)
						)
						(arc
							(start -0.2794 0.1778)
							(mid -0.249642 0.249642)
							(end -0.1778 0.2794)
						)
						(arc
							(start 0.1778 0.2794)
							(mid 0.249642 0.249642)
							(end 0.2794 0.1778)
						)
						(arc
							(start 0.2794 -0.1778)
							(mid 0.249642 -0.249642)
							(end 0.1778 -0.2794)
						)
					)
					(width 0)
					(fill yes)
				)
			)
		)
	)
	(footprint ""
		(layer "F.Cu")
		(at 234.061 -350.770952 -90)
		(property "Reference" "R9449"
			(at 0 0 270)
			(layer "F.SilkS")
			(hide yes)
			(effects
				(font
					(size 1.27 1.27)
				)
			)
		)
		(property "Value" "330R2F-GP"
			(at 0.064008 -3.993896 270)
			(unlocked yes)
			(layer "F.Fab")
			(hide yes)
			(effects
				(font
					(size 1.016 1.016)
					(thickness 0.1524)
				)
			)
		)
		(property "Device Type" "R402H16"
			(at 0.064008 -5.517896 270)
			(unlocked yes)
			(layer "F.Fab")
			(hide yes)
			(effects
				(font
					(size 1.016 1.016)
					(thickness 0.1524)
				)
			)
		)
		(duplicate_pad_numbers_are_jumpers no)
		(fp_line
			(start -0.508 -0.9398)
			(end -0.508 0.9398)
			(stroke
				(width 0.1524)
				(type default)
			)
			(layer "F.SilkS")
		)
		(fp_line
			(start 0.508 -0.9398)
			(end -0.508 -0.9398)
			(stroke
				(width 0.1524)
				(type default)
			)
			(layer "F.SilkS")
		)
		(fp_rect
			(start -0.508 0.9398)
			(end 0.508 -0.9398)
			(stroke
				(width 0)
				(type default)
			)
			(fill no)
			(layer "F.CrtYd")
		)
		(fp_rect
			(start -0.508 0.9398)
			(end 0.508 -0.9398)
			(stroke
				(width 0)
				(type default)
			)
			(fill no)
			(layer "F.Fab")
		)
		(pad "1" smd custom
			(at 0 -0.4445 270)
			(size 0.1397 0.1397)
			(layers "F.Cu" "F.Mask" "F.Paste")
			(net "P3V3")
			(options
				(clearance outline)
				(anchor circle)
			)
			(primitives
				(gr_poly
					(pts
						(arc
							(start -0.1778 -0.2794)
							(mid -0.249642 -0.249642)
							(end -0.2794 -0.1778)
						)
						(arc
							(start -0.2794 0.1778)
							(mid -0.249642 0.249642)
							(end -0.1778 0.2794)
						)
						(arc
							(start 0.1778 0.2794)
							(mid 0.249642 0.249642)
							(end 0.2794 0.1778)
						)
						(arc
							(start 0.2794 -0.1778)
							(mid 0.249642 -0.249642)
							(end 0.1778 -0.2794)
						)
					)
					(width 0)
					(fill yes)
				)
			)
		)
		(pad "2" smd custom
			(at 0 0.4445 270)
			(size 0.1397 0.1397)
			(layers "F.Cu" "F.Mask" "F.Paste")
			(net "DRV_ATTN_1")
			(options
				(clearance outline)
				(anchor circle)
			)
			(primitives
				(gr_poly
					(pts
						(arc
							(start -0.1778 -0.2794)
							(mid -0.249642 -0.249642)
							(end -0.2794 -0.1778)
						)
						(arc
							(start -0.2794 0.1778)
							(mid -0.249642 0.249642)
							(end -0.1778 0.2794)
						)
						(arc
							(start 0.1778 0.2794)
							(mid 0.249642 0.249642)
							(end 0.2794 0.1778)
						)
						(arc
							(start 0.2794 -0.1778)
							(mid 0.249642 -0.249642)
							(end 0.1778 -0.2794)
						)
					)
					(width 0)
					(fill yes)
				)
			)
		)
	)
	(footprint ""
		(layer "F.Cu")
		(at 207.391 -300.228 180)
		(property "Reference" "R9501"
			(at 0 0 180)
			(layer "F.SilkS")
			(hide yes)
			(effects
				(font
					(size 1.27 1.27)
				)
			)
		)
		(property "Value" "4K7R2J-2-GP"
			(at 0.064008 -3.993896 180)
			(unlocked yes)
			(layer "F.Fab")
			(hide yes)
			(effects
				(font
					(size 1.016 1.016)
					(thickness 0.1524)
				)
			)
		)
		(property "Device Type" "R402H16"
			(at 0.064008 -5.517896 180)
			(unlocked yes)
			(layer "F.Fab")
			(hide yes)
			(effects
				(font
					(size 1.016 1.016)
					(thickness 0.1524)
				)
			)
		)
		(duplicate_pad_numbers_are_jumpers no)
		(fp_line
			(start 0.508 -0.9398)
			(end -0.508 -0.9398)
			(stroke
				(width 0.1524)
				(type default)
			)
			(layer "F.SilkS")
		)
		(fp_line
			(start -0.508 -0.9398)
			(end -0.508 0.9398)
			(stroke
				(width 0.1524)
				(type default)
			)
			(layer "F.SilkS")
		)
		(fp_rect
			(start -0.508 0.9398)
			(end 0.508 -0.9398)
			(stroke
				(width 0)
				(type default)
			)
			(fill no)
			(layer "F.CrtYd")
		)
		(fp_rect
			(start -0.508 0.9398)
			(end 0.508 -0.9398)
			(stroke
				(width 0)
				(type default)
			)
			(fill no)
			(layer "F.Fab")
		)
		(pad "1" smd custom
			(at 0 -0.4445 180)
			(size 0.1397 0.1397)
			(layers "F.Cu" "F.Mask" "F.Paste")
			(net "P3V3")
			(options
				(clearance outline)
				(anchor circle)
			)
			(primitives
				(gr_poly
					(pts
						(arc
							(start -0.1778 -0.2794)
							(mid -0.249642 -0.249642)
							(end -0.2794 -0.1778)
						)
						(arc
							(start -0.2794 0.1778)
							(mid -0.249642 0.249642)
							(end -0.1778 0.2794)
						)
						(arc
							(start 0.1778 0.2794)
							(mid 0.249642 0.249642)
							(end 0.2794 0.1778)
						)
						(arc
							(start 0.2794 -0.1778)
							(mid 0.249642 -0.249642)
							(end 0.1778 -0.2794)
						)
					)
					(width 0)
					(fill yes)
				)
			)
		)
		(pad "2" smd custom
			(at 0 0.4445 180)
			(size 0.1397 0.1397)
			(layers "F.Cu" "F.Mask" "F.Paste")
			(net "SSD2_PWREN")
			(options
				(clearance outline)
				(anchor circle)
			)
			(primitives
				(gr_poly
					(pts
						(arc
							(start -0.1778 -0.2794)
							(mid -0.249642 -0.249642)
							(end -0.2794 -0.1778)
						)
						(arc
							(start -0.2794 0.1778)
							(mid -0.249642 0.249642)
							(end -0.1778 0.2794)
						)
						(arc
							(start 0.1778 0.2794)
							(mid 0.249642 0.249642)
							(end 0.2794 0.1778)
						)
						(arc
							(start 0.2794 -0.1778)
							(mid 0.249642 -0.249642)
							(end 0.1778 -0.2794)
						)
					)
					(width 0)
					(fill yes)
				)
			)
		)
	)
	(footprint ""
		(layer "F.Cu")
		(at 25.3238 -87.122)
		(property "Reference" "C391"
			(at 0 0 0)
			(layer "F.SilkS")
			(hide yes)
			(effects
				(font
					(size 1.27 1.27)
				)
			)
		)
		(property "Value" "SCD1U25V2KX-2-GP"
			(at 1.1811 -2.7051 0)
			(unlocked yes)
			(layer "F.Fab")
			(hide yes)
			(effects
				(font
					(size 1.016 1.016)
					(thickness 0.1524)
				)
			)
		)
		(property "Device Type" "C402H22"
			(at 1.1811 -4.2291 0)
			(unlocked yes)
			(layer "F.Fab")
			(hide yes)
			(effects
				(font
					(size 1.016 1.016)
					(thickness 0.1524)
				)
			)
		)
		(duplicate_pad_numbers_are_jumpers no)
		(fp_rect
			(start -0.4318 0.9525)
			(end 0.4318 -0.9525)
			(stroke
				(width 0)
				(type default)
			)
			(fill no)
			(layer "F.CrtYd")
		)
		(fp_rect
			(start -0.4318 0.9525)
			(end 0.4318 -0.9525)
			(stroke
				(width 0)
				(type default)
			)
			(fill no)
			(layer "F.Fab")
		)
		(pad "1" smd custom
			(at 0 -0.4445)
			(size 0.1524 0.1524)
			(layers "F.Cu" "F.Mask" "F.Paste")
			(net "P12V")
			(options
				(clearance outline)
				(anchor circle)
			)
			(primitives
				(gr_poly
					(pts
						(arc
							(start 0.3048 -0.2032)
							(mid 0.275042 -0.275042)
							(end 0.2032 -0.3048)
						)
						(arc
							(start -0.2032 -0.3048)
							(mid -0.275042 -0.275042)
							(end -0.3048 -0.2032)
						)
						(arc
							(start -0.3048 0.2032)
							(mid -0.275042 0.275042)
							(end -0.2032 0.3048)
						)
						(arc
							(start 0.2032 0.3048)
							(mid 0.275042 0.275042)
							(end 0.3048 0.2032)
						)
					)
					(width 0)
					(fill yes)
				)
			)
		)
		(pad "2" smd custom
			(at 0 0.4445)
			(size 0.1524 0.1524)
			(layers "F.Cu" "F.Mask" "F.Paste")
			(net "SW_SSD9_N")
			(options
				(clearance outline)
				(anchor circle)
			)
			(primitives
				(gr_poly
					(pts
						(arc
							(start 0.3048 -0.2032)
							(mid 0.275042 -0.275042)
							(end 0.2032 -0.3048)
						)
						(arc
							(start -0.2032 -0.3048)
							(mid -0.275042 -0.275042)
							(end -0.3048 -0.2032)
						)
						(arc
							(start -0.3048 0.2032)
							(mid -0.275042 0.275042)
							(end -0.2032 0.3048)
						)
						(arc
							(start 0.2032 0.3048)
							(mid 0.275042 0.275042)
							(end 0.3048 0.2032)
						)
					)
					(width 0)
					(fill yes)
				)
			)
		)
	)
	(footprint ""
		(layer "F.Cu")
		(at 91.313 -219.456 180)
		(property "Reference" "R9091"
			(at 0 0 180)
			(layer "F.SilkS")
			(hide yes)
			(effects
				(font
					(size 1.27 1.27)
				)
			)
		)
		(property "Value" "27R2F-GP"
			(at 0.064008 -3.993896 180)
			(unlocked yes)
			(layer "F.Fab")
			(hide yes)
			(effects
				(font
					(size 1.016 1.016)
					(thickness 0.1524)
				)
			)
		)
		(property "Device Type" "R402H16"
			(at 0.064008 -5.517896 180)
			(unlocked yes)
			(layer "F.Fab")
			(hide yes)
			(effects
				(font
					(size 1.016 1.016)
					(thickness 0.1524)
				)
			)
		)
		(duplicate_pad_numbers_are_jumpers no)
		(fp_line
			(start 0.508 -0.9398)
			(end -0.508 -0.9398)
			(stroke
				(width 0.1524)
				(type default)
			)
			(layer "F.SilkS")
		)
		(fp_line
			(start -0.508 -0.9398)
			(end -0.508 0.9398)
			(stroke
				(width 0.1524)
				(type default)
			)
			(layer "F.SilkS")
		)
		(fp_rect
			(start -0.508 0.9398)
			(end 0.508 -0.9398)
			(stroke
				(width 0)
				(type default)
			)
			(fill no)
			(layer "F.CrtYd")
		)
		(fp_rect
			(start -0.508 0.9398)
			(end 0.508 -0.9398)
			(stroke
				(width 0)
				(type default)
			)
			(fill no)
			(layer "F.Fab")
		)
		(pad "1" smd custom
			(at 0 -0.4445 180)
			(size 0.1397 0.1397)
			(layers "F.Cu" "F.Mask" "F.Paste")
			(net "PE_CLK_100M_DR12_2_R_P")
			(options
				(clearance outline)
				(anchor circle)
			)
			(primitives
				(gr_poly
					(pts
						(arc
							(start -0.1778 -0.2794)
							(mid -0.249642 -0.249642)
							(end -0.2794 -0.1778)
						)
						(arc
							(start -0.2794 0.1778)
							(mid -0.249642 0.249642)
							(end -0.1778 0.2794)
						)
						(arc
							(start 0.1778 0.2794)
							(mid 0.249642 0.249642)
							(end 0.2794 0.1778)
						)
						(arc
							(start 0.2794 -0.1778)
							(mid 0.249642 -0.249642)
							(end 0.1778 -0.2794)
						)
					)
					(width 0)
					(fill yes)
				)
			)
		)
		(pad "2" smd custom
			(at 0 0.4445 180)
			(size 0.1397 0.1397)
			(layers "F.Cu" "F.Mask" "F.Paste")
			(net "PE_CLK100M_DR12_2_P")
			(options
				(clearance outline)
				(anchor circle)
			)
			(primitives
				(gr_poly
					(pts
						(arc
							(start -0.1778 -0.2794)
							(mid -0.249642 -0.249642)
							(end -0.2794 -0.1778)
						)
						(arc
							(start -0.2794 0.1778)
							(mid -0.249642 0.249642)
							(end -0.1778 0.2794)
						)
						(arc
							(start 0.1778 0.2794)
							(mid 0.249642 0.249642)
							(end 0.2794 0.1778)
						)
						(arc
							(start 0.2794 -0.1778)
							(mid 0.249642 -0.249642)
							(end 0.1778 -0.2794)
						)
					)
					(width 0)
					(fill yes)
				)
			)
		)
	)
	(footprint ""
		(layer "F.Cu")
		(at 77.1144 -366.522)
		(property "Reference" "SR988"
			(at 0 0 0)
			(layer "F.SilkS")
			(hide yes)
			(effects
				(font
					(size 1.27 1.27)
				)
			)
		)
		(property "Value" "2KR2F-3-GP"
			(at 0.064008 -3.993896 0)
			(unlocked yes)
			(layer "F.Fab")
			(hide yes)
			(effects
				(font
					(size 1.016 1.016)
					(thickness 0.1524)
				)
			)
		)
		(property "Device Type" "R402H16"
			(at 0.064008 -5.517896 0)
			(unlocked yes)
			(layer "F.Fab")
			(hide yes)
			(effects
				(font
					(size 1.016 1.016)
					(thickness 0.1524)
				)
			)
		)
		(duplicate_pad_numbers_are_jumpers no)
		(fp_line
			(start -0.508 -0.9398)
			(end -0.508 0.9398)
			(stroke
				(width 0.1524)
				(type default)
			)
			(layer "F.SilkS")
		)
		(fp_line
			(start 0.508 -0.9398)
			(end -0.508 -0.9398)
			(stroke
				(width 0.1524)
				(type default)
			)
			(layer "F.SilkS")
		)
		(fp_rect
			(start -0.508 0.9398)
			(end 0.508 -0.9398)
			(stroke
				(width 0)
				(type default)
			)
			(fill no)
			(layer "F.CrtYd")
		)
		(fp_rect
			(start -0.508 0.9398)
			(end 0.508 -0.9398)
			(stroke
				(width 0)
				(type default)
			)
			(fill no)
			(layer "F.Fab")
		)
		(pad "1" smd custom
			(at 0 -0.4445)
			(size 0.1397 0.1397)
			(layers "F.Cu" "F.Mask" "F.Paste")
			(net "P3V3")
			(options
				(clearance outline)
				(anchor circle)
			)
			(primitives
				(gr_poly
					(pts
						(arc
							(start -0.1778 -0.2794)
							(mid -0.249642 -0.249642)
							(end -0.2794 -0.1778)
						)
						(arc
							(start -0.2794 0.1778)
							(mid -0.249642 0.249642)
							(end -0.1778 0.2794)
						)
						(arc
							(start 0.1778 0.2794)
							(mid 0.249642 0.249642)
							(end 0.2794 0.1778)
						)
						(arc
							(start 0.2794 -0.1778)
							(mid 0.249642 -0.249642)
							(end 0.1778 -0.2794)
						)
					)
					(width 0)
					(fill yes)
				)
			)
		)
		(pad "2" smd custom
			(at 0 0.4445)
			(size 0.1397 0.1397)
			(layers "F.Cu" "F.Mask" "F.Paste")
			(net "SCL_DR5")
			(options
				(clearance outline)
				(anchor circle)
			)
			(primitives
				(gr_poly
					(pts
						(arc
							(start -0.1778 -0.2794)
							(mid -0.249642 -0.249642)
							(end -0.2794 -0.1778)
						)
						(arc
							(start -0.2794 0.1778)
							(mid -0.249642 0.249642)
							(end -0.1778 0.2794)
						)
						(arc
							(start 0.1778 0.2794)
							(mid 0.249642 0.249642)
							(end 0.2794 0.1778)
						)
						(arc
							(start 0.2794 -0.1778)
							(mid 0.249642 -0.249642)
							(end 0.1778 -0.2794)
						)
					)
					(width 0)
					(fill yes)
				)
			)
		)
	)
	(footprint ""
		(layer "F.Cu")
		(at 45.466 -140.589 -90)
		(property "Reference" "C344"
			(at 0 0 270)
			(layer "F.SilkS")
			(hide yes)
			(effects
				(font
					(size 1.27 1.27)
				)
			)
		)
		(property "Value" "SCD1U16V2KX-3GP"
			(at 1.1811 -2.7051 270)
			(unlocked yes)
			(layer "F.Fab")
			(hide yes)
			(effects
				(font
					(size 1.016 1.016)
					(thickness 0.1524)
				)
			)
		)
		(property "Device Type" "C402H22"
			(at 1.1811 -4.2291 270)
			(unlocked yes)
			(layer "F.Fab")
			(hide yes)
			(effects
				(font
					(size 1.016 1.016)
					(thickness 0.1524)
				)
			)
		)
		(duplicate_pad_numbers_are_jumpers no)
		(fp_rect
			(start -0.4318 0.9525)
			(end 0.4318 -0.9525)
			(stroke
				(width 0)
				(type default)
			)
			(fill no)
			(layer "F.CrtYd")
		)
		(fp_rect
			(start -0.4318 0.9525)
			(end 0.4318 -0.9525)
			(stroke
				(width 0)
				(type default)
			)
			(fill no)
			(layer "F.Fab")
		)
		(pad "1" smd custom
			(at 0 -0.4445 270)
			(size 0.1524 0.1524)
			(layers "F.Cu" "F.Mask" "F.Paste")
			(net "P3V3")
			(options
				(clearance outline)
				(anchor circle)
			)
			(primitives
				(gr_poly
					(pts
						(arc
							(start 0.3048 -0.2032)
							(mid 0.275042 -0.275042)
							(end 0.2032 -0.3048)
						)
						(arc
							(start -0.2032 -0.3048)
							(mid -0.275042 -0.275042)
							(end -0.3048 -0.2032)
						)
						(arc
							(start -0.3048 0.2032)
							(mid -0.275042 0.275042)
							(end -0.2032 0.3048)
						)
						(arc
							(start 0.2032 0.3048)
							(mid 0.275042 0.275042)
							(end 0.3048 0.2032)
						)
					)
					(width 0)
					(fill yes)
				)
			)
		)
		(pad "2" smd custom
			(at 0 0.4445 270)
			(size 0.1524 0.1524)
			(layers "F.Cu" "F.Mask" "F.Paste")
			(net "GND")
			(options
				(clearance outline)
				(anchor circle)
			)
			(primitives
				(gr_poly
					(pts
						(arc
							(start 0.3048 -0.2032)
							(mid 0.275042 -0.275042)
							(end 0.2032 -0.3048)
						)
						(arc
							(start -0.2032 -0.3048)
							(mid -0.275042 -0.275042)
							(end -0.3048 -0.2032)
						)
						(arc
							(start -0.3048 0.2032)
							(mid -0.275042 0.275042)
							(end -0.2032 0.3048)
						)
						(arc
							(start 0.2032 0.3048)
							(mid 0.275042 0.275042)
							(end 0.3048 0.2032)
						)
					)
					(width 0)
					(fill yes)
				)
			)
		)
	)
)
